# T6G (Grand Teton) — schematic netlist excerpt (pin names and nets, part order shuffled) for the footprints in the layout excerpt that follows; sources: Cadence DE-HDL packaged netlist, KiCad conversion of 04192023_DAF0TMB3IC0_F0TG_MB_C_brd_V02_OCP.brd

R136  Q_RES  10K 1% EMPTY  pkg 0402LF  page 83 : A = FM_APML_MUX2_SEL ; B = GND

U217  74LVC1G126SE7  74LVC1G126SE-7 IC  pkg SOT353_0-65_2X1-25  page 139
  OE  = PU_OCP_V3_2_WAKE_OE
  A  = IRQ_LVC3_OCP_V3_2_WAKE_N
  GND  = GND
  Y  = OCP_V3_2_WAKE_BUFF_N
  VCC  = P3V3_AUX

(kicad_pcb
	(version 20260206)
	(generator "pcbnew")
	(generator_version "10.0")
	(general
		(thickness 1.6)
		(legacy_teardrops no)
	)
	(paper "A4")
	(title_block
		(title "04192023_DAF0TMB3IC0_F0TG_MB_C_brd_V02_OCP.brd")
		(comment 1 "Grand Teton / footprints 1047-1048 of 8354")
	)
	(layers
		(0 "F.Cu" signal "TOP")
		(4 "In1.Cu" signal "GND")
		(6 "In2.Cu" signal "IN1")
		(8 "In3.Cu" signal "GND1")
		(10 "In4.Cu" signal "IN2")
		(12 "In5.Cu" signal "GND2")
		(14 "In6.Cu" signal "IN3")
		(16 "In7.Cu" signal "GND3")
		(18 "In8.Cu" signal "VCC")
		(20 "In9.Cu" signal "VCC1")
		(22 "In10.Cu" signal "GND4")
		(24 "In11.Cu" signal "IN4")
		(26 "In12.Cu" signal "GND5")
		(28 "In13.Cu" signal "IN5")
		(30 "In14.Cu" signal "GND6")
		(32 "In15.Cu" signal "IN6")
		(34 "In16.Cu" signal "GND7")
		(2 "B.Cu" signal "BOTTOM")
		(9 "F.Adhes" user "F.Adhesive")
		(11 "B.Adhes" user "B.Adhesive")
		(13 "F.Paste" user "Package Geometry/Pastemask Top")
		(15 "B.Paste" user "Package Geometry/Pastemask Bottom")
		(5 "F.SilkS" user "Ref Des/Silkscreen Top")
		(7 "B.SilkS" user "Ref Des/Silkscreen Bottom")
		(1 "F.Mask" user "Board Geometry/Soldermask Top")
		(3 "B.Mask" user "Board Geometry/Soldermask Bottom")
		(17 "Dwgs.User" user "User.Drawings")
		(19 "Cmts.User" user "User.Comments")
		(21 "Eco1.User" user "User.Eco1")
		(23 "Eco2.User" user "User.Eco2")
		(25 "Edge.Cuts" user "Board Geometry/Outline")
		(27 "Margin" user)
		(31 "F.CrtYd" user "Package Geometry/Place Bound Top")
		(29 "B.CrtYd" user "Package Geometry/Place Bound Bottom")
		(35 "F.Fab" user "Ref Des/Assembly Top")
		(33 "B.Fab" user "Ref Des/Assembly Bottom")
	)
	(footprint ""
		(layer "F.Cu")
		(at 98.52533 -39.465758 180)
		(property "Reference" "U217"
			(at 1.229868 1.844548 0)
			(unlocked yes)
			(layer "F.SilkS")
			(effects
				(font
					(size 0.7874 0.5842)
					(thickness 0.1524)
				)
				(justify left)
			)
		)
		(property "Value" ""
			(at 0 0 180)
			(layer "F.Fab")
			(effects
				(font
					(size 1.27 1.27)
				)
			)
		)
		(duplicate_pad_numbers_are_jumpers no)
		(fp_line
			(start 1.400048 1.100074)
			(end -1.400048 1.100074)
			(stroke
				(width 0.1524)
				(type default)
			)
			(layer "F.SilkS")
		)
		(fp_line
			(start 1.400048 -1.100074)
			(end 1.400048 1.100074)
			(stroke
				(width 0.1524)
				(type default)
			)
			(layer "F.SilkS")
		)
		(fp_line
			(start 1.400048 -1.100074)
			(end -1.400048 -1.100074)
			(stroke
				(width 0.1524)
				(type default)
			)
			(layer "F.SilkS")
		)
		(fp_line
			(start -1.400048 1.100074)
			(end -1.400048 -1.100074)
			(stroke
				(width 0.1524)
				(type default)
			)
			(layer "F.SilkS")
		)
		(fp_poly
			(pts
				(xy -0.51562 -2.307082) (xy -1.02362 -1.291082) (xy -1.53162 -2.307082)
			)
			(stroke
				(width 0)
				(type default)
			)
			(fill yes)
			(layer "F.SilkS")
		)
		(fp_line
			(start 0.674878 1.100074)
			(end -0.674878 1.100074)
			(stroke
				(width 0.1)
				(type default)
			)
			(layer "F.Fab")
		)
		(fp_line
			(start 0.674878 -1.100074)
			(end 0.674878 1.100074)
			(stroke
				(width 0.1)
				(type default)
			)
			(layer "F.Fab")
		)
		(fp_line
			(start -0.674878 1.100074)
			(end -0.674878 -1.100074)
			(stroke
				(width 0.1)
				(type default)
			)
			(layer "F.Fab")
		)
		(fp_line
			(start -0.674878 -1.100074)
			(end 0.674878 -1.100074)
			(stroke
				(width 0.1)
				(type default)
			)
			(layer "F.Fab")
		)
		(fp_poly
			(pts
				(xy -1.590548 -0.649986) (xy -2.606548 -1.157986) (xy -2.606548 -0.141986)
			)
			(stroke
				(width 0)
				(type default)
			)
			(fill yes)
			(layer "F.Fab")
		)
		(pad "1" smd rect
			(at -0.94996 -0.649986 90)
			(size 0.4318 0.6096)
			(layers "F.Cu" "F.Mask" "F.Paste")
			(net "PU_OCP_V3_2_WAKE_OE")
		)
		(pad "2" smd rect
			(at -0.94996 0 90)
			(size 0.4318 0.6096)
			(layers "F.Cu" "F.Mask" "F.Paste")
			(net "IRQ_LVC3_OCP_V3_2_WAKE_N")
		)
		(pad "3" smd rect
			(at -0.94996 0.649986 90)
			(size 0.4318 0.6096)
			(layers "F.Cu" "F.Mask" "F.Paste")
			(net "GND")
		)
		(pad "4" smd rect
			(at 0.94996 0.649986 90)
			(size 0.4318 0.6096)
			(layers "F.Cu" "F.Mask" "F.Paste")
			(net "OCP_V3_2_WAKE_BUFF_N")
		)
		(pad "5" smd rect
			(at 0.94996 -0.649986 90)
			(size 0.4318 0.6096)
			(layers "F.Cu" "F.Mask" "F.Paste")
			(net "P3V3_AUX")
		)
	)
	(footprint ""
		(layer "F.Cu")
		(at 212.993732 -116.732812 180)
		(property "Reference" "R136"
			(at 0 0 180)
			(layer "F.SilkS")
			(hide yes)
			(effects
				(font
					(size 1.27 1.27)
				)
			)
		)
		(property "Value" ""
			(at 0 0 180)
			(layer "F.Fab")
			(effects
				(font
					(size 1.27 1.27)
				)
			)
		)
		(duplicate_pad_numbers_are_jumpers no)
		(fp_line
			(start 0.7874 0.4064)
			(end -0.7874 0.4064)
			(stroke
				(width 0.1524)
				(type default)
			)
			(layer "F.SilkS")
		)
		(fp_line
			(start 0.7874 -0.4064)
			(end 0.7874 0.4064)
			(stroke
				(width 0.1524)
				(type default)
			)
			(layer "F.SilkS")
		)
		(fp_line
			(start -0.7874 0.4064)
			(end -0.7874 -0.4064)
			(stroke
				(width 0.1524)
				(type default)
			)
			(layer "F.SilkS")
		)
		(fp_line
			(start -0.7874 -0.4064)
			(end 0.7874 -0.4064)
			(stroke
				(width 0.1524)
				(type default)
			)
			(layer "F.SilkS")
		)
		(fp_line
			(start 0.67945 0.3048)
			(end 0.120396 0.3048)
			(stroke
				(width 0.1)
				(type default)
			)
			(layer "F.Fab")
		)
		(fp_line
			(start 0.67945 -0.3048)
			(end 0.67945 0.3048)
			(stroke
				(width 0.1)
				(type default)
			)
			(layer "F.Fab")
		)
		(fp_line
			(start 0.12065 -0.2794)
			(end 0.12065 -0.3048)
			(stroke
				(width 0.1)
				(type default)
			)
			(layer "F.Fab")
		)
		(fp_line
			(start 0.12065 -0.3048)
			(end 0.67945 -0.3048)
			(stroke
				(width 0.1)
				(type default)
			)
			(layer "F.Fab")
		)
		(fp_line
			(start 0.120396 0.3048)
			(end 0.120396 0.2794)
			(stroke
				(width 0.1)
				(type default)
			)
			(layer "F.Fab")
		)
		(fp_line
			(start 0.120396 0.2794)
			(end -0.12065 0.2794)
			(stroke
				(width 0.1)
				(type default)
			)
			(layer "F.Fab")
		)
		(fp_line
			(start -0.12065 0.3048)
			(end -0.67945 0.3048)
			(stroke
				(width 0.1)
				(type default)
			)
			(layer "F.Fab")
		)
		(fp_line
			(start -0.12065 0.2794)
			(end -0.12065 0.3048)
			(stroke
				(width 0.1)
				(type default)
			)
			(layer "F.Fab")
		)
		(fp_line
			(start -0.12065 -0.2794)
			(end 0.12065 -0.2794)
			(stroke
				(width 0.1)
				(type default)
			)
			(layer "F.Fab")
		)
		(fp_line
			(start -0.12065 -0.305054)
			(end -0.12065 -0.2794)
			(stroke
				(width 0.1)
				(type default)
			)
			(layer "F.Fab")
		)
		(fp_line
			(start -0.67945 0.3048)
			(end -0.67945 -0.305054)
			(stroke
				(width 0.1)
				(type default)
			)
			(layer "F.Fab")
		)
		(fp_line
			(start -0.67945 -0.305054)
			(end -0.12065 -0.305054)
			(stroke
				(width 0.1)
				(type default)
			)
			(layer "F.Fab")
		)
		(pad "1" smd circle
			(at -0.40005 0 180)
			(size 0 0)
			(layers "F.Cu" "F.Mask" "F.Paste")
			(net "FM_APML_MUX2_SEL")
		)
		(pad "2" smd circle
			(at 0.40005 0 180)
			(size 0 0)
			(layers "F.Cu" "F.Mask" "F.Paste")
			(net "GND")
		)
	)
)
